(kicad_pcb
	(version 20260206)
	(generator "pcbnew")
	(generator_version "10.0")
	(general
		(thickness 1.6)
		(legacy_teardrops no)
	)
	(paper "A4")
	(title_block
		(title "Bryce Canyon_F.DPB_16315-1-OCP.brd")
		(comment 1 "Bryce Canyon / footprints 309-312 of 2223")
	)
	(layers
		(0 "F.Cu" signal "TOP")
		(4 "In1.Cu" signal "L2GND")
		(6 "In2.Cu" signal "L3")
		(8 "In3.Cu" signal "L4GND")
		(10 "In4.Cu" signal "L5")
		(12 "In5.Cu" signal "L6VCC")
		(14 "In6.Cu" signal "L7VCC")
		(16 "In7.Cu" signal "L8")
		(18 "In8.Cu" signal "L9GND")
		(20 "In9.Cu" signal "L10")
		(22 "In10.Cu" signal "L11GND")
		(2 "B.Cu" signal "BOTTOM")
		(9 "F.Adhes" user "F.Adhesive")
		(11 "B.Adhes" user "B.Adhesive")
		(13 "F.Paste" user "Package Geometry/Pastemask Top")
		(15 "B.Paste" user "Package Geometry/Pastemask Bottom")
		(5 "F.SilkS" user "Ref Des/Silkscreen Top")
		(7 "B.SilkS" user "Ref Des/Silkscreen Bottom")
		(1 "F.Mask" user "Board Geometry/Soldermask Top")
		(3 "B.Mask" user "Board Geometry/Soldermask Bottom")
		(17 "Dwgs.User" user "User.Drawings")
		(19 "Cmts.User" user "User.Comments")
		(21 "Eco1.User" user "User.Eco1")
		(23 "Eco2.User" user "User.Eco2")
		(25 "Edge.Cuts" user "Board Geometry/Outline")
		(27 "Margin" user)
		(31 "F.CrtYd" user "Package Geometry/Place Bound Top")
		(29 "B.CrtYd" user "Package Geometry/Place Bound Bottom")
		(35 "F.Fab" user "Ref Des/Assembly Top")
		(33 "B.Fab" user "Ref Des/Assembly Bottom")
	)
	(footprint ""
		(layer "F.Cu")
		(at 7.333742 -291.042344 90)
		(property "Reference" "R553"
			(at 0 0 90)
			(layer "F.SilkS")
			(hide yes)
			(effects
				(font
					(size 1.27 1.27)
				)
			)
		)
		(property "Value" "4K7R2J-2-GP"
			(at 0.064008 -3.993896 90)
			(unlocked yes)
			(layer "F.Fab")
			(hide yes)
			(effects
				(font
					(size 1.016 1.016)
					(thickness 0.1524)
				)
			)
		)
		(property "Device Type" "R402H16"
			(at 0.064008 -5.517896 90)
			(unlocked yes)
			(layer "F.Fab")
			(hide yes)
			(effects
				(font
					(size 1.016 1.016)
					(thickness 0.1524)
				)
			)
		)
		(duplicate_pad_numbers_are_jumpers no)
		(fp_line
			(start 0.508 -0.9398)
			(end -0.508 -0.9398)
			(stroke
				(width 0.1524)
				(type default)
			)
			(layer "F.SilkS")
		)
		(fp_line
			(start -0.508 -0.9398)
			(end -0.508 0.9398)
			(stroke
				(width 0.1524)
				(type default)
			)
			(layer "F.SilkS")
		)
		(fp_rect
			(start -0.508 0.9398)
			(end 0.508 -0.9398)
			(stroke
				(width 0)
				(type default)
			)
			(fill no)
			(layer "F.CrtYd")
		)
		(fp_rect
			(start -0.508 0.9398)
			(end 0.508 -0.9398)
			(stroke
				(width 0)
				(type default)
			)
			(fill no)
			(layer "F.Fab")
		)
		(pad "1" smd custom
			(at 0 -0.4445 90)
			(size 0.1397 0.1397)
			(layers "F.Cu" "F.Mask" "F.Paste")
			(net "DRIVE_B_24_FLT_LED")
			(options
				(clearance outline)
				(anchor circle)
			)
			(primitives
				(gr_poly
					(pts
						(arc
							(start -0.1778 -0.2794)
							(mid -0.249642 -0.249642)
							(end -0.2794 -0.1778)
						)
						(arc
							(start -0.2794 0.1778)
							(mid -0.249642 0.249642)
							(end -0.1778 0.2794)
						)
						(arc
							(start 0.1778 0.2794)
							(mid 0.249642 0.249642)
							(end 0.2794 0.1778)
						)
						(arc
							(start 0.2794 -0.1778)
							(mid 0.249642 -0.249642)
							(end 0.1778 -0.2794)
						)
					)
					(width 0)
					(fill yes)
				)
			)
		)
		(pad "2" smd custom
			(at 0 0.4445 90)
			(size 0.1397 0.1397)
			(layers "F.Cu" "F.Mask" "F.Paste")
			(net "GND")
			(options
				(clearance outline)
				(anchor circle)
			)
			(primitives
				(gr_poly
					(pts
						(arc
							(start -0.1778 -0.2794)
							(mid -0.249642 -0.249642)
							(end -0.2794 -0.1778)
						)
						(arc
							(start -0.2794 0.1778)
							(mid -0.249642 0.249642)
							(end -0.1778 0.2794)
						)
						(arc
							(start 0.1778 0.2794)
							(mid 0.249642 0.249642)
							(end 0.2794 0.1778)
						)
						(arc
							(start 0.2794 -0.1778)
							(mid 0.249642 -0.249642)
							(end 0.1778 -0.2794)
						)
					)
					(width 0)
					(fill yes)
				)
			)
		)
	)
	(footprint ""
		(layer "F.Cu")
		(at 478.930462 -288.841942)
		(property "Reference" "R382"
			(at 0 0 0)
			(layer "F.SilkS")
			(hide yes)
			(effects
				(font
					(size 1.27 1.27)
				)
			)
		)
		(property "Value" "2R6F-GP"
			(at -0.0508 -4.8514 0)
			(unlocked yes)
			(layer "F.Fab")
			(hide yes)
			(effects
				(font
					(size 1.016 1.016)
					(thickness 0.1524)
				)
			)
		)
		(property "Device Type" "R1206H26"
			(at 0 -6.3754 0)
			(unlocked yes)
			(layer "F.Fab")
			(hide yes)
			(effects
				(font
					(size 1.016 1.016)
					(thickness 0.1524)
				)
			)
		)
		(duplicate_pad_numbers_are_jumpers no)
		(fp_line
			(start -1.016 -2.2352)
			(end 1.016 -2.2352)
			(stroke
				(width 0.1524)
				(type default)
			)
			(layer "F.SilkS")
		)
		(fp_line
			(start -1.016 2.2352)
			(end -1.016 -2.2352)
			(stroke
				(width 0.1524)
				(type default)
			)
			(layer "F.SilkS")
		)
		(fp_line
			(start 1.016 -2.2352)
			(end 1.016 2.2352)
			(stroke
				(width 0.1524)
				(type default)
			)
			(layer "F.SilkS")
		)
		(fp_line
			(start 1.016 2.2352)
			(end -1.016 2.2352)
			(stroke
				(width 0.1524)
				(type default)
			)
			(layer "F.SilkS")
		)
		(fp_rect
			(start -1.0922 2.3114)
			(end 1.0922 -2.3114)
			(stroke
				(width 0)
				(type default)
			)
			(fill no)
			(layer "F.CrtYd")
		)
		(fp_poly
			(pts
				(xy -1.0922 -2.3114) (xy 1.0922 -2.3114) (xy 1.0922 2.3114) (xy -1.0922 2.3114)
			)
			(stroke
				(width 0)
				(type default)
			)
			(fill no)
			(layer "F.Fab")
		)
		(pad "1" smd rect
			(at 0 -1.397)
			(size 1.651 1.27)
			(layers "F.Cu" "F.Mask" "F.Paste")
			(net "P5V_HDD11")
		)
		(pad "2" smd rect
			(at 0 1.397)
			(size 1.651 1.27)
			(layers "F.Cu" "F.Mask" "F.Paste")
			(net "5V_PRE_11")
		)
	)
	(footprint ""
		(layer "F.Cu")
		(at 357.100124 -172.909992 -90)
		(property "Reference" "HDDSAS19"
			(at 0 0 270)
			(layer "F.SilkS")
			(hide yes)
			(effects
				(font
					(size 1.27 1.27)
				)
			)
		)
		(property "Value" "SKT-SAS15P-14P-45-GP"
			(at -20.7645 -8.9789 270)
			(unlocked yes)
			(layer "F.Fab")
			(hide yes)
			(effects
				(font
					(size 1.016 1.016)
					(thickness 0.1524)
				)
			)
		)
		(property "Device Type" "10120818-001C-TRLF"
			(at -20.7645 -10.5029 270)
			(unlocked yes)
			(layer "F.Fab")
			(hide yes)
			(effects
				(font
					(size 1.016 1.016)
					(thickness 0.1524)
				)
			)
		)
		(duplicate_pad_numbers_are_jumpers no)
		(fp_line
			(start 1.651 4.2926)
			(end 1.651 3.0099)
			(stroke
				(width 0.1524)
				(type default)
			)
			(layer "F.SilkS")
		)
		(fp_line
			(start 8.509 4.2926)
			(end 1.651 4.2926)
			(stroke
				(width 0.1524)
				(type default)
			)
			(layer "F.SilkS")
		)
		(fp_line
			(start -23.4188 3.0099)
			(end -23.4188 -3.2512)
			(stroke
				(width 0.1524)
				(type default)
			)
			(layer "F.SilkS")
		)
		(fp_line
			(start 1.651 3.0099)
			(end -23.4188 3.0099)
			(stroke
				(width 0.1524)
				(type default)
			)
			(layer "F.SilkS")
		)
		(fp_line
			(start 8.509 3.0099)
			(end 8.509 4.2926)
			(stroke
				(width 0.1524)
				(type default)
			)
			(layer "F.SilkS")
		)
		(fp_line
			(start 23.4188 3.0099)
			(end 8.509 3.0099)
			(stroke
				(width 0.1524)
				(type default)
			)
			(layer "F.SilkS")
		)
		(fp_line
			(start -23.4188 -3.2512)
			(end 23.4188 -3.2512)
			(stroke
				(width 0.1524)
				(type default)
			)
			(layer "F.SilkS")
		)
		(fp_line
			(start 23.4188 -3.2512)
			(end 23.4188 3.0099)
			(stroke
				(width 0.1524)
				(type default)
			)
			(layer "F.SilkS")
		)
		(fp_line
			(start 15.5067 -3.3401)
			(end 16.2687 -3.3401)
			(stroke
				(width 0.3302)
				(type default)
			)
			(layer "F.SilkS")
		)
		(fp_poly
			(pts
				(xy 15.868904 -3.230372) (xy 16.503904 -3.865372) (xy 15.233904 -3.865372)
			)
			(stroke
				(width 0)
				(type default)
			)
			(fill yes)
			(layer "F.SilkS")
		)
		(fp_poly
			(pts
				(xy -22.8727 -2.7559) (xy 22.8727 -2.7559) (xy 22.8727 2.7559) (xy 8.255 2.7559) (xy 8.255 3.5179)
				(xy 1.905 3.5179) (xy 1.905 2.7559) (xy -22.8727 2.7559)
			)
			(stroke
				(width 0)
				(type default)
			)
			(fill no)
			(layer "F.CrtYd")
		)
		(fp_poly
			(pts
				(xy 1.397 4.5466) (xy 1.397 3.2639) (xy -23.6728 3.2639) (xy -23.6728 -3.5052) (xy 23.6728 -3.5052)
				(xy 23.6728 -0.00635) (xy 22.8727 -0.00635) (xy 22.8727 -2.7559) (xy -22.8727 -2.7559) (xy -22.8727 2.7559)
				(xy 1.905 2.7559) (xy 1.905 3.5179) (xy 8.255 3.5179) (xy 8.255 2.7559) (xy 22.8727 2.7559) (xy 22.8727 0.00635)
				(xy 23.6728 0.00635) (xy 23.6728 3.2639) (xy 8.763 3.2639) (xy 8.763 4.5466)
			)
			(stroke
				(width 0)
				(type default)
			)
			(fill no)
			(layer "F.CrtYd")
		)
		(fp_poly
			(pts
				(xy 1.397 4.5466) (xy 1.397 3.2639) (xy -23.6728 3.2639) (xy -23.6728 -3.5052) (xy 23.6728 -3.5052)
				(xy 23.6728 3.2639) (xy 8.763 3.2639) (xy 8.763 4.5466)
			)
			(stroke
				(width 0)
				(type default)
			)
			(fill no)
			(layer "F.Fab")
		)
		(pad "" np_thru_hole circle
			(at -18.874994 0 270)
			(size 0.254 0.254)
			(drill 1.3462)
			(layers "*.Cu" "*.Mask")
			(clearance 0.9017)
			(thermal_gap 0.9017)
		)
		(pad "" np_thru_hole circle
			(at 18.874994 0 270)
			(size 0.254 0.254)
			(drill 0.9398)
			(layers "*.Cu" "*.Mask")
			(clearance 0.6985)
			(thermal_gap 0.6985)
		)
		(pad "G1" smd rect
			(at 21.874988 0 270)
			(size 2.5908 2.5908)
			(layers "F.Cu" "F.Mask" "F.Paste")
			(net "GND")
		)
		(pad "G2" smd rect
			(at -21.874988 0 270)
			(size 2.5908 2.5908)
			(layers "F.Cu" "F.Mask" "F.Paste")
			(net "GND")
		)
		(pad "P1" smd rect
			(at 1.905 -1.82499 270)
			(size 0.6096 2.3622)
			(layers "F.Cu" "F.Mask" "F.Paste")
			(net "Net_2116")
		)
		(pad "P2" smd rect
			(at 0.635 -1.82499 270)
			(size 0.6096 2.3622)
			(layers "F.Cu" "F.Mask" "F.Paste")
			(net "Net_2117")
		)
		(pad "P3" smd rect
			(at -0.635 -1.82499 270)
			(size 0.6096 2.3622)
			(layers "F.Cu" "F.Mask" "F.Paste")
			(net "Net_2118")
		)
		(pad "P4" smd rect
			(at -1.905 -1.82499 270)
			(size 0.6096 2.3622)
			(layers "F.Cu" "F.Mask" "F.Paste")
			(net "GND")
		)
		(pad "P5" smd rect
			(at -3.175 -1.82499 270)
			(size 0.6096 2.3622)
			(layers "F.Cu" "F.Mask" "F.Paste")
			(net "HDD_PRSNT_19")
		)
		(pad "P6" smd rect
			(at -4.445 -1.82499 270)
			(size 0.6096 2.3622)
			(layers "F.Cu" "F.Mask" "F.Paste")
			(net "GND")
		)
		(pad "P7" smd rect
			(at -5.715 -1.82499 270)
			(size 0.6096 2.3622)
			(layers "F.Cu" "F.Mask" "F.Paste")
			(net "5V_PRE_19")
		)
		(pad "P8" smd rect
			(at -6.985 -1.82499 270)
			(size 0.6096 2.3622)
			(layers "F.Cu" "F.Mask" "F.Paste")
			(net "P5V_HDD19")
		)
		(pad "P9" smd rect
			(at -8.255 -1.82499 270)
			(size 0.6096 2.3622)
			(layers "F.Cu" "F.Mask" "F.Paste")
			(net "P5V_HDD19")
		)
		(pad "P10" smd rect
			(at -9.525 -1.82499 270)
			(size 0.6096 2.3622)
			(layers "F.Cu" "F.Mask" "F.Paste")
			(net "GND")
		)
		(pad "P11" smd rect
			(at -10.795 -1.82499 270)
			(size 0.6096 2.3622)
			(layers "F.Cu" "F.Mask" "F.Paste")
			(net "ACT_HDD_19")
		)
		(pad "P12" smd rect
			(at -12.065 -1.82499 270)
			(size 0.6096 2.3622)
			(layers "F.Cu" "F.Mask" "F.Paste")
			(net "GND")
		)
		(pad "P13" smd rect
			(at -13.335 -1.82499 270)
			(size 0.6096 2.3622)
			(layers "F.Cu" "F.Mask" "F.Paste")
			(net "12V_PRE_19")
		)
		(pad "P14" smd rect
			(at -14.605 -1.82499 270)
			(size 0.6096 2.3622)
			(layers "F.Cu" "F.Mask" "F.Paste")
			(net "P12V_HDD19")
		)
		(pad "P15" smd rect
			(at -15.875 -1.82499 270)
			(size 0.6096 2.3622)
			(layers "F.Cu" "F.Mask" "F.Paste")
			(net "P12V_HDD19")
		)
		(pad "S1" smd rect
			(at 15.875 -1.82499 270)
			(size 0.6096 2.3622)
			(layers "F.Cu" "F.Mask" "F.Paste")
			(net "GND")
		)
		(pad "S2" smd rect
			(at 14.605 -1.82499 270)
			(size 0.6096 2.3622)
			(layers "F.Cu" "F.Mask" "F.Paste")
			(net "SAS_HDD_RX_P19")
		)
		(pad "S3" smd rect
			(at 13.335 -1.82499 270)
			(size 0.6096 2.3622)
			(layers "F.Cu" "F.Mask" "F.Paste")
			(net "SAS_HDD_RX_N19")
		)
		(pad "S4" smd rect
			(at 12.065 -1.82499 270)
			(size 0.6096 2.3622)
			(layers "F.Cu" "F.Mask" "F.Paste")
			(net "GND")
		)
		(pad "S5" smd rect
			(at 10.795 -1.82499 270)
			(size 0.6096 2.3622)
			(layers "F.Cu" "F.Mask" "F.Paste")
			(net "PHY_DRV_A_TO_SCC_A_19_DN")
		)
		(pad "S6" smd rect
			(at 9.525 -1.82499 270)
			(size 0.6096 2.3622)
			(layers "F.Cu" "F.Mask" "F.Paste")
			(net "PHY_DRV_A_TO_SCC_A_19_DP")
		)
		(pad "S7" smd rect
			(at 8.255 -1.82499 270)
			(size 0.6096 2.3622)
			(layers "F.Cu" "F.Mask" "F.Paste")
			(net "GND")
		)
		(pad "S8" smd rect
			(at 7.480046 2.845054 270)
			(size 0.508 2.3622)
			(layers "F.Cu" "F.Mask" "F.Paste")
			(net "GND")
		)
		(pad "S9" smd rect
			(at 6.679946 2.845054 270)
			(size 0.508 2.3622)
			(layers "F.Cu" "F.Mask" "F.Paste")
			(net "Net_457")
		)
		(pad "S10" smd rect
			(at 5.8801 2.845054 270)
			(size 0.508 2.3622)
			(layers "F.Cu" "F.Mask" "F.Paste")
			(net "Net_349")
		)
		(pad "S11" smd rect
			(at 5.08 2.845054 270)
			(size 0.508 2.3622)
			(layers "F.Cu" "F.Mask" "F.Paste")
			(net "GND")
		)
		(pad "S12" smd rect
			(at 4.2799 2.845054 270)
			(size 0.508 2.3622)
			(layers "F.Cu" "F.Mask" "F.Paste")
			(net "Net_385")
		)
		(pad "S13" smd rect
			(at 3.480054 2.845054 270)
			(size 0.508 2.3622)
			(layers "F.Cu" "F.Mask" "F.Paste")
			(net "Net_421")
		)
		(pad "S14" smd rect
			(at 2.679954 2.845054 270)
			(size 0.508 2.3622)
			(layers "F.Cu" "F.Mask" "F.Paste")
			(net "GND")
		)
		(zone
			(layer "F.Cu")
			(hatch none 0.5)
			(connect_pads
				(clearance 0)
			)
			(min_thickness 0.25)
			(keepout
				(tracks not_allowed)
				(vias allowed)
				(pads allowed)
				(copperpour not_allowed)
				(footprints allowed)
			)
			(placement
				(enabled no)
				(sheetname "")
			)
			(fill
				(thermal_gap 0.5)
				(thermal_bridge_width 0.5)
				(island_removal_mode 0)
			)
			(polygon
				(pts
					(xy 360.757724 -189.648592) (xy 353.683824 -189.648592) (xy 353.683824 -196.582792) (xy 354.788724 -196.582792)
					(xy 354.788724 -192.467992) (xy 359.411524 -192.467992) (xy 359.411524 -196.582792) (xy 360.757724 -196.582792)
				)
			)
		)
		(zone
			(layer "F.Cu")
			(hatch none 0.5)
			(connect_pads
				(clearance 0)
			)
			(min_thickness 0.25)
			(keepout
				(tracks allowed)
				(vias not_allowed)
				(pads allowed)
				(copperpour not_allowed)
				(footprints allowed)
			)
			(placement
				(enabled no)
				(sheetname "")
			)
			(fill
				(thermal_gap 0.5)
				(thermal_bridge_width 0.5)
				(island_removal_mode 0)
			)
			(polygon
				(pts
					(xy 360.757724 -189.648592) (xy 353.683824 -189.648592) (xy 353.683824 -196.582792) (xy 354.788724 -196.582792)
					(xy 354.788724 -192.467992) (xy 359.411524 -192.467992) (xy 359.411524 -196.582792) (xy 360.757724 -196.582792)
				)
			)
		)
		(zone
			(layer "F.Cu")
			(hatch none 0.5)
			(connect_pads
				(clearance 0)
			)
			(min_thickness 0.25)
			(keepout
				(tracks allowed)
				(vias not_allowed)
				(pads allowed)
				(copperpour not_allowed)
				(footprints allowed)
			)
			(placement
				(enabled no)
				(sheetname "")
			)
			(fill
				(thermal_gap 0.5)
				(thermal_bridge_width 0.5)
				(island_removal_mode 0)
			)
			(polygon
				(pts
					(xy 360.757724 -156.171392) (xy 353.683824 -156.171392) (xy 353.683824 -149.237192) (xy 354.788724 -149.237192)
					(xy 354.788724 -153.351992) (xy 359.411524 -153.351992) (xy 359.411524 -149.237192) (xy 360.757724 -149.237192)
				)
			)
		)
		(zone
			(layer "F.Cu")
			(hatch none 0.5)
			(connect_pads
				(clearance 0)
			)
			(min_thickness 0.25)
			(keepout
				(tracks not_allowed)
				(vias allowed)
				(pads allowed)
				(copperpour not_allowed)
				(footprints allowed)
			)
			(placement
				(enabled no)
				(sheetname "")
			)
			(fill
				(thermal_gap 0.5)
				(thermal_bridge_width 0.5)
				(island_removal_mode 0)
			)
			(polygon
				(pts
					(xy 360.757724 -156.171392) (xy 353.683824 -156.171392) (xy 353.683824 -149.237192) (xy 354.788724 -149.237192)
					(xy 354.788724 -153.351992) (xy 359.411524 -153.351992) (xy 359.411524 -149.237192) (xy 360.757724 -149.237192)
				)
			)
		)
		(zone
			(layers "F.Cu" "B.Cu" "In1.Cu" "In2.Cu" "In3.Cu" "In4.Cu" "In5.Cu" "In6.Cu"
				"In7.Cu" "In8.Cu" "In9.Cu" "In10.Cu"
			)
			(hatch none 0.5)
			(connect_pads
				(clearance 0)
			)
			(min_thickness 0.25)
			(keepout
				(tracks not_allowed)
				(vias allowed)
				(pads allowed)
				(copperpour not_allowed)
				(footprints allowed)
			)
			(placement
				(enabled no)
				(sheetname "")
			)
			(fill
				(thermal_gap 0.5)
				(thermal_bridge_width 0.5)
				(island_removal_mode 0)
			)
			(polygon
				(pts
					(arc
						(start 357.874824 -154.034998)
						(mid 356.325424 -154.034998)
						(end 357.874824 -154.034998)
					)
				)
			)
		)
		(zone
			(layers "F.Cu" "B.Cu" "In1.Cu" "In2.Cu" "In3.Cu" "In4.Cu" "In5.Cu" "In6.Cu"
				"In7.Cu" "In8.Cu" "In9.Cu" "In10.Cu"
			)
			(hatch none 0.5)
			(connect_pads
				(clearance 0)
			)
			(min_thickness 0.25)
			(keepout
				(tracks not_allowed)
				(vias allowed)
				(pads allowed)
				(copperpour not_allowed)
				(footprints allowed)
			)
			(placement
				(enabled no)
				(sheetname "")
			)
			(fill
				(thermal_gap 0.5)
				(thermal_bridge_width 0.5)
				(island_removal_mode 0)
			)
			(polygon
				(pts
					(arc
						(start 358.078024 -191.784986)
						(mid 356.122224 -191.784986)
						(end 358.078024 -191.784986)
					)
				)
			)
		)
	)
	(footprint ""
		(layer "F.Cu")
		(at 363.909102 -180.826918 180)
		(property "Reference" "C288"
			(at 0 0 180)
			(layer "F.SilkS")
			(hide yes)
			(effects
				(font
					(size 1.27 1.27)
				)
			)
		)
		(property "Value" "SC10U16V6KX-2GP"
			(at -0.0762 -5.1308 180)
			(unlocked yes)
			(layer "F.Fab")
			(hide yes)
			(effects
				(font
					(size 1.016 1.016)
					(thickness 0.1524)
				)
			)
		)
		(property "Device Type" "C1206H71"
			(at -0.127 -6.6548 180)
			(unlocked yes)
			(layer "F.Fab")
			(hide yes)
			(effects
				(font
					(size 1.016 1.016)
					(thickness 0.1524)
				)
			)
		)
		(duplicate_pad_numbers_are_jumpers no)
		(fp_line
			(start 1.016 2.2352)
			(end -1.016 2.2352)
			(stroke
				(width 0.1524)
				(type default)
			)
			(layer "F.SilkS")
		)
		(fp_line
			(start 1.016 0.8382)
			(end 1.016 2.2352)
			(stroke
				(width 0.1524)
				(type default)
			)
			(layer "F.SilkS")
		)
		(fp_line
			(start 1.016 -2.2352)
			(end 1.016 -0.8382)
			(stroke
				(width 0.1524)
				(type default)
			)
			(layer "F.SilkS")
		)
		(fp_line
			(start -1.016 2.2352)
			(end -1.016 0.8382)
			(stroke
				(width 0.1524)
				(type default)
			)
			(layer "F.SilkS")
		)
		(fp_line
			(start -1.016 -0.8382)
			(end -1.016 -2.2352)
			(stroke
				(width 0.1524)
				(type default)
			)
			(layer "F.SilkS")
		)
		(fp_line
			(start -1.016 -2.2352)
			(end 1.016 -2.2352)
			(stroke
				(width 0.1524)
				(type default)
			)
			(layer "F.SilkS")
		)
		(fp_rect
			(start -1.0922 2.3114)
			(end 1.0922 -2.3114)
			(stroke
				(width 0)
				(type default)
			)
			(fill no)
			(layer "F.CrtYd")
		)
		(fp_poly
			(pts
				(xy 1.0922 -2.3114) (xy 1.0922 2.3114) (xy -1.0922 2.3114) (xy -1.0922 -2.3114)
			)
			(stroke
				(width 0)
				(type default)
			)
			(fill no)
			(layer "F.Fab")
		)
		(pad "1" smd rect
			(at 0 -1.397 180)
			(size 1.651 1.27)
			(layers "F.Cu" "F.Mask" "F.Paste")
			(net "P5V_HDD19")
		)
		(pad "2" smd rect
			(at 0 1.397 180)
			(size 1.651 1.27)
			(layers "F.Cu" "F.Mask" "F.Paste")
			(net "GND")
		)
	)
)
